# T6G (Grand Teton) — schematic netlist excerpt (pin names and nets, part order shuffled) for the footprints in the layout excerpt that follows; sources: Cadence DE-HDL packaged netlist, KiCad conversion of 04192023_DAF0TMB3IC0_F0TG_MB_C_brd_V02_OCP.brd

C720  Q_CAP_DIFFBUS  DIFF BUS_0.22UF 6.3V 20% X6S  pkg C0201  page 66 : \1\ = P5E_CPU1_P1_TX_C_DN<10> ; \2\ = P5E_CPU1_P1_TX_DN<10>

U9  TPS71715DCKR  EMPTY  pkg SC70-5XB  page 187
  \in\  = P1V5_BAT_IN
  GND  = GND
  EN  = BAT_LDO_EN
  \nr||fb\  = U9_NR
  \out\  = P1V5_BAT_OUT

R6735  Q_RES  1K 1% CHIP  pkg 0201LF  page 185 : A = P1V8_CPU1_RT_1D ; B = SMB_RT_CPU1_P1_ROM_R_SDA
R1079  Q_RES  4.7K 5% CHIP  pkg 0201LF  page 298 : A = JTAG_TEST_MODE_RT_CPU0_P2 ; B = GND

(kicad_pcb
	(version 20260206)
	(generator "pcbnew")
	(generator_version "10.0")
	(general
		(thickness 1.6)
		(legacy_teardrops no)
	)
	(paper "A4")
	(title_block
		(title "04192023_DAF0TMB3IC0_F0TG_MB_C_brd_V02_OCP.brd")
		(comment 1 "Grand Teton / footprints 1898-1901 of 8354")
	)
	(layers
		(0 "F.Cu" signal "TOP")
		(4 "In1.Cu" signal "GND")
		(6 "In2.Cu" signal "IN1")
		(8 "In3.Cu" signal "GND1")
		(10 "In4.Cu" signal "IN2")
		(12 "In5.Cu" signal "GND2")
		(14 "In6.Cu" signal "IN3")
		(16 "In7.Cu" signal "GND3")
		(18 "In8.Cu" signal "VCC")
		(20 "In9.Cu" signal "VCC1")
		(22 "In10.Cu" signal "GND4")
		(24 "In11.Cu" signal "IN4")
		(26 "In12.Cu" signal "GND5")
		(28 "In13.Cu" signal "IN5")
		(30 "In14.Cu" signal "GND6")
		(32 "In15.Cu" signal "IN6")
		(34 "In16.Cu" signal "GND7")
		(2 "B.Cu" signal "BOTTOM")
		(9 "F.Adhes" user "F.Adhesive")
		(11 "B.Adhes" user "B.Adhesive")
		(13 "F.Paste" user "Package Geometry/Pastemask Top")
		(15 "B.Paste" user "Package Geometry/Pastemask Bottom")
		(5 "F.SilkS" user "Ref Des/Silkscreen Top")
		(7 "B.SilkS" user "Ref Des/Silkscreen Bottom")
		(1 "F.Mask" user "Board Geometry/Soldermask Top")
		(3 "B.Mask" user "Board Geometry/Soldermask Bottom")
		(17 "Dwgs.User" user "User.Drawings")
		(19 "Cmts.User" user "User.Comments")
		(21 "Eco1.User" user "User.Eco1")
		(23 "Eco2.User" user "User.Eco2")
		(25 "Edge.Cuts" user "Board Geometry/Outline")
		(27 "Margin" user)
		(31 "F.CrtYd" user "Package Geometry/Place Bound Top")
		(29 "B.CrtYd" user "Package Geometry/Place Bound Bottom")
		(35 "F.Fab" user "Ref Des/Assembly Top")
		(33 "B.Fab" user "Ref Des/Assembly Bottom")
	)
	(footprint ""
		(layer "F.Cu")
		(at 304.931572 -25.62225)
		(property "Reference" "U9"
			(at -1.8034 -1.819148 0)
			(unlocked yes)
			(layer "F.SilkS")
			(effects
				(font
					(size 0.7874 0.5842)
					(thickness 0.1524)
				)
				(justify left)
			)
		)
		(property "Value" ""
			(at 0 0 0)
			(layer "F.Fab")
			(effects
				(font
					(size 1.27 1.27)
				)
			)
		)
		(duplicate_pad_numbers_are_jumpers no)
		(fp_line
			(start -1.684274 -1.074928)
			(end -0.381 -1.074928)
			(stroke
				(width 0.1524)
				(type default)
			)
			(layer "F.SilkS")
		)
		(fp_line
			(start -1.684274 1.074928)
			(end -1.684274 -1.074928)
			(stroke
				(width 0.1524)
				(type default)
			)
			(layer "F.SilkS")
		)
		(fp_line
			(start -0.381 -1.074928)
			(end 0 -0.625094)
			(stroke
				(width 0.1524)
				(type default)
			)
			(layer "F.SilkS")
		)
		(fp_line
			(start 0 -0.625094)
			(end 0.381 -1.074928)
			(stroke
				(width 0.1524)
				(type default)
			)
			(layer "F.SilkS")
		)
		(fp_line
			(start 0.381 -1.074928)
			(end 1.684274 -1.074928)
			(stroke
				(width 0.1524)
				(type default)
			)
			(layer "F.SilkS")
		)
		(fp_line
			(start 1.684274 -1.074928)
			(end 1.684274 1.074928)
			(stroke
				(width 0.1524)
				(type default)
			)
			(layer "F.SilkS")
		)
		(fp_line
			(start 1.684274 1.074928)
			(end -1.684274 1.074928)
			(stroke
				(width 0.1524)
				(type default)
			)
			(layer "F.SilkS")
		)
		(fp_poly
			(pts
				(xy -2.637282 -0.903986) (xy -2.637282 -0.395986) (xy -1.875282 -0.649986)
			)
			(stroke
				(width 0)
				(type default)
			)
			(fill yes)
			(layer "F.SilkS")
		)
		(fp_line
			(start -0.700024 -1.074928)
			(end -0.700024 1.074928)
			(stroke
				(width 0.1)
				(type default)
			)
			(layer "F.Fab")
		)
		(fp_line
			(start -0.700024 1.074928)
			(end 0.700024 1.074928)
			(stroke
				(width 0.1)
				(type default)
			)
			(layer "F.Fab")
		)
		(fp_line
			(start 0.700024 -1.074928)
			(end -0.700024 -1.074928)
			(stroke
				(width 0.1)
				(type default)
			)
			(layer "F.Fab")
		)
		(fp_line
			(start 0.700024 1.074928)
			(end 0.700024 -1.074928)
			(stroke
				(width 0.1)
				(type default)
			)
			(layer "F.Fab")
		)
		(fp_poly
			(pts
				(xy -2.637282 -0.903986) (xy -2.637282 -0.395986) (xy -1.875282 -0.649986)
			)
			(stroke
				(width 0)
				(type default)
			)
			(fill yes)
			(layer "F.Fab")
		)
		(pad "1" smd rect
			(at -1.100074 -0.649986 270)
			(size 0.4064 0.9144)
			(layers "F.Cu" "F.Mask" "F.Paste")
			(net "P1V5_BAT_IN")
		)
		(pad "2" smd rect
			(at -1.100074 0 270)
			(size 0.4064 0.9144)
			(layers "F.Cu" "F.Mask" "F.Paste")
			(net "GND")
		)
		(pad "3" smd rect
			(at -1.100074 0.649986 270)
			(size 0.4064 0.9144)
			(layers "F.Cu" "F.Mask" "F.Paste")
			(net "BAT_LDO_EN")
		)
		(pad "4" smd rect
			(at 1.100074 0.649986 270)
			(size 0.4064 0.9144)
			(layers "F.Cu" "F.Mask" "F.Paste")
			(net "U9_NR")
		)
		(pad "5" smd rect
			(at 1.100074 -0.649986 270)
			(size 0.4064 0.9144)
			(layers "F.Cu" "F.Mask" "F.Paste")
			(net "P1V5_BAT_OUT")
		)
	)
	(footprint ""
		(layer "F.Cu")
		(at 402.214842 -403.603206 -90)
		(property "Reference" "R1079"
			(at 0 0 270)
			(layer "F.SilkS")
			(hide yes)
			(effects
				(font
					(size 1.27 1.27)
				)
			)
		)
		(property "Value" ""
			(at 0 0 270)
			(layer "F.Fab")
			(effects
				(font
					(size 1.27 1.27)
				)
			)
		)
		(duplicate_pad_numbers_are_jumpers no)
		(fp_line
			(start -0.32512 0.175006)
			(end -0.32512 -0.175006)
			(stroke
				(width 0.1)
				(type default)
			)
			(layer "F.Fab")
		)
		(fp_line
			(start 0.32512 0.175006)
			(end -0.32512 0.175006)
			(stroke
				(width 0.1)
				(type default)
			)
			(layer "F.Fab")
		)
		(fp_line
			(start -0.32512 -0.175006)
			(end 0.32512 -0.175006)
			(stroke
				(width 0.1)
				(type default)
			)
			(layer "F.Fab")
		)
		(fp_line
			(start 0.32512 -0.175006)
			(end 0.32512 0.175006)
			(stroke
				(width 0.1)
				(type default)
			)
			(layer "F.Fab")
		)
		(pad "1" smd rect
			(at -0.2667 0 270)
			(size 0.3048 0.381)
			(layers "F.Cu" "F.Mask" "F.Paste")
			(net "JTAG_TEST_MODE_RT_CPU0_P2")
		)
		(pad "2" smd rect
			(at 0.2667 0 90)
			(size 0.3048 0.381)
			(layers "F.Cu" "F.Mask" "F.Paste")
			(net "GND")
		)
	)
	(footprint ""
		(layer "F.Cu")
		(at 95.151702 -375.49963 -90)
		(property "Reference" "C720"
			(at 0 0 270)
			(layer "F.SilkS")
			(hide yes)
			(effects
				(font
					(size 1.27 1.27)
				)
			)
		)
		(property "Value" ""
			(at 0 0 270)
			(layer "F.Fab")
			(effects
				(font
					(size 1.27 1.27)
				)
			)
		)
		(duplicate_pad_numbers_are_jumpers no)
		(fp_line
			(start -0.299974 0.150114)
			(end -0.299974 -0.150114)
			(stroke
				(width 0.1)
				(type default)
			)
			(layer "F.Fab")
		)
		(fp_line
			(start 0.299974 0.150114)
			(end -0.299974 0.150114)
			(stroke
				(width 0.1)
				(type default)
			)
			(layer "F.Fab")
		)
		(fp_line
			(start -0.299974 -0.150114)
			(end 0.299974 -0.150114)
			(stroke
				(width 0.1)
				(type default)
			)
			(layer "F.Fab")
		)
		(fp_line
			(start 0.299974 -0.150114)
			(end 0.299974 0.150114)
			(stroke
				(width 0.1)
				(type default)
			)
			(layer "F.Fab")
		)
		(pad "1" smd rect
			(at -0.2667 0 270)
			(size 0.3048 0.381)
			(layers "F.Cu" "F.Mask" "F.Paste")
			(net "P5E_CPU1_P1_TX_C_DN<10>")
		)
		(pad "2" smd rect
			(at 0.2667 0 270)
			(size 0.3048 0.381)
			(layers "F.Cu" "F.Mask" "F.Paste")
			(net "P5E_CPU1_P1_TX_DN<10>")
		)
	)
	(footprint ""
		(layer "F.Cu")
		(at 108.4199 -395.769084 90)
		(property "Reference" "R6735"
			(at 0 0 90)
			(layer "F.SilkS")
			(hide yes)
			(effects
				(font
					(size 1.27 1.27)
				)
			)
		)
		(property "Value" ""
			(at 0 0 90)
			(layer "F.Fab")
			(effects
				(font
					(size 1.27 1.27)
				)
			)
		)
		(duplicate_pad_numbers_are_jumpers no)
		(fp_line
			(start 0.32512 -0.175006)
			(end 0.32512 0.175006)
			(stroke
				(width 0.1)
				(type default)
			)
			(layer "F.Fab")
		)
		(fp_line
			(start -0.32512 -0.175006)
			(end 0.32512 -0.175006)
			(stroke
				(width 0.1)
				(type default)
			)
			(layer "F.Fab")
		)
		(fp_line
			(start 0.32512 0.175006)
			(end -0.32512 0.175006)
			(stroke
				(width 0.1)
				(type default)
			)
			(layer "F.Fab")
		)
		(fp_line
			(start -0.32512 0.175006)
			(end -0.32512 -0.175006)
			(stroke
				(width 0.1)
				(type default)
			)
			(layer "F.Fab")
		)
		(pad "1" smd rect
			(at -0.2667 0 90)
			(size 0.3048 0.381)
			(layers "F.Cu" "F.Mask" "F.Paste")
			(net "P1V8_CPU1_RT_1D")
		)
		(pad "2" smd rect
			(at 0.2667 0 270)
			(size 0.3048 0.381)
			(layers "F.Cu" "F.Mask" "F.Paste")
			(net "SMB_RT_CPU1_P1_ROM_R_SDA")
		)
	)
)
